# S9S_MB_2U (Grand Teton) — schematic netlist excerpt (pin names and nets, part order shuffled) for the footprints in the layout excerpt that follows; sources: Cadence DE-HDL packaged netlist, KiCad conversion of 03242023_DA0F0TMBIJ0_F0T_Motherboard_J_brd_V01_OCP.brd

R572  Q_RES  2.2 1% CHIP  pkg 0603LF  page 206 : A = P3V3_DB2000_FB_VDD ; B = P3V3_DB2000_VDDA
C78  Q_CAP  2.2UF 6.3V 20% X6S  pkg C0402  page 111 : A = P3V3_AUX ; B = GND

(kicad_pcb
	(version 20260206)
	(generator "pcbnew")
	(generator_version "10.0")
	(general
		(thickness 1.6)
		(legacy_teardrops no)
	)
	(paper "A4")
	(title_block
		(title "03242023_DA0F0TMBIJ0_F0T_Motherboard_J_brd_V01_OCP.brd")
		(comment 1 "Grand Teton / footprints 4183-4184 of 6105")
	)
	(layers
		(0 "F.Cu" signal "TOP")
		(4 "In1.Cu" signal "GND")
		(6 "In2.Cu" signal "IN1")
		(8 "In3.Cu" signal "GND1")
		(10 "In4.Cu" signal "IN2")
		(12 "In5.Cu" signal "GND2")
		(14 "In6.Cu" signal "IN3")
		(16 "In7.Cu" signal "GND3")
		(18 "In8.Cu" signal "VCC")
		(20 "In9.Cu" signal "VCC1")
		(22 "In10.Cu" signal "GND4")
		(24 "In11.Cu" signal "IN4")
		(26 "In12.Cu" signal "GND5")
		(28 "In13.Cu" signal "IN5")
		(30 "In14.Cu" signal "GND6")
		(32 "In15.Cu" signal "IN6")
		(34 "In16.Cu" signal "GND7")
		(2 "B.Cu" signal "BOTTOM")
		(9 "F.Adhes" user "F.Adhesive")
		(11 "B.Adhes" user "B.Adhesive")
		(13 "F.Paste" user "Package Geometry/Pastemask Top")
		(15 "B.Paste" user "Package Geometry/Pastemask Bottom")
		(5 "F.SilkS" user "Ref Des/Silkscreen Top")
		(7 "B.SilkS" user "Ref Des/Silkscreen Bottom")
		(1 "F.Mask" user "Board Geometry/Soldermask Top")
		(3 "B.Mask" user "Board Geometry/Soldermask Bottom")
		(17 "Dwgs.User" user "User.Drawings")
		(19 "Cmts.User" user "User.Comments")
		(21 "Eco1.User" user "User.Eco1")
		(23 "Eco2.User" user "User.Eco2")
		(25 "Edge.Cuts" user "Board Geometry/Outline")
		(27 "Margin" user)
		(31 "F.CrtYd" user "Package Geometry/Place Bound Top")
		(29 "B.CrtYd" user "Package Geometry/Place Bound Bottom")
		(35 "F.Fab" user "Ref Des/Assembly Top")
		(33 "B.Fab" user "Ref Des/Assembly Bottom")
	)
	(footprint ""
		(layer "B.Cu")
		(at 189.039754 -319.450974 180)
		(property "Reference" "C78"
			(at 0 0 0)
			(layer "B.SilkS")
			(hide yes)
			(effects
				(font
					(size 1.27 1.27)
				)
				(justify mirror)
			)
		)
		(property "Value" ""
			(at 0 0 0)
			(layer "B.Fab")
			(effects
				(font
					(size 1.27 1.27)
				)
				(justify mirror)
			)
		)
		(duplicate_pad_numbers_are_jumpers no)
		(fp_line
			(start 0.7874 0.4064)
			(end 0.7874 -0.4064)
			(stroke
				(width 0.1524)
				(type default)
			)
			(layer "B.SilkS")
		)
		(fp_line
			(start 0.7874 -0.4064)
			(end -0.7874 -0.4064)
			(stroke
				(width 0.1524)
				(type default)
			)
			(layer "B.SilkS")
		)
		(fp_line
			(start -0.7874 0.4064)
			(end 0.7874 0.4064)
			(stroke
				(width 0.1524)
				(type default)
			)
			(layer "B.SilkS")
		)
		(fp_line
			(start -0.7874 -0.4064)
			(end -0.7874 0.4064)
			(stroke
				(width 0.1524)
				(type default)
			)
			(layer "B.SilkS")
		)
		(fp_line
			(start 0.67945 0.3048)
			(end 0.67945 -0.305054)
			(stroke
				(width 0.1)
				(type default)
			)
			(layer "B.Fab")
		)
		(fp_line
			(start 0.67945 -0.305054)
			(end 0.12065 -0.305054)
			(stroke
				(width 0.1)
				(type default)
			)
			(layer "B.Fab")
		)
		(fp_line
			(start 0.12065 0.3048)
			(end 0.67945 0.3048)
			(stroke
				(width 0.1)
				(type default)
			)
			(layer "B.Fab")
		)
		(fp_line
			(start 0.12065 0.2794)
			(end 0.12065 0.3048)
			(stroke
				(width 0.1)
				(type default)
			)
			(layer "B.Fab")
		)
		(fp_line
			(start 0.12065 -0.2794)
			(end -0.12065 -0.2794)
			(stroke
				(width 0.1)
				(type default)
			)
			(layer "B.Fab")
		)
		(fp_line
			(start 0.12065 -0.305054)
			(end 0.12065 -0.2794)
			(stroke
				(width 0.1)
				(type default)
			)
			(layer "B.Fab")
		)
		(fp_line
			(start -0.120396 0.3048)
			(end -0.120396 0.2794)
			(stroke
				(width 0.1)
				(type default)
			)
			(layer "B.Fab")
		)
		(fp_line
			(start -0.120396 0.2794)
			(end 0.12065 0.2794)
			(stroke
				(width 0.1)
				(type default)
			)
			(layer "B.Fab")
		)
		(fp_line
			(start -0.12065 -0.2794)
			(end -0.12065 -0.3048)
			(stroke
				(width 0.1)
				(type default)
			)
			(layer "B.Fab")
		)
		(fp_line
			(start -0.12065 -0.3048)
			(end -0.67945 -0.3048)
			(stroke
				(width 0.1)
				(type default)
			)
			(layer "B.Fab")
		)
		(fp_line
			(start -0.67945 0.3048)
			(end -0.120396 0.3048)
			(stroke
				(width 0.1)
				(type default)
			)
			(layer "B.Fab")
		)
		(fp_line
			(start -0.67945 -0.3048)
			(end -0.67945 0.3048)
			(stroke
				(width 0.1)
				(type default)
			)
			(layer "B.Fab")
		)
		(pad "1" smd circle
			(at 0.40005 0)
			(size 0 0)
			(layers "B.Cu" "B.Mask" "B.Paste")
			(net "P3V3_AUX")
		)
		(pad "2" smd circle
			(at -0.40005 0)
			(size 0 0)
			(layers "B.Cu" "B.Mask" "B.Paste")
			(net "GND")
		)
	)
	(footprint ""
		(layer "B.Cu")
		(at 233.55681 -123.015248 -90)
		(property "Reference" "R572"
			(at 0 0 90)
			(layer "B.SilkS")
			(hide yes)
			(effects
				(font
					(size 1.27 1.27)
				)
				(justify mirror)
			)
		)
		(property "Value" ""
			(at 0 0 90)
			(layer "B.Fab")
			(effects
				(font
					(size 1.27 1.27)
				)
				(justify mirror)
			)
		)
		(duplicate_pad_numbers_are_jumpers no)
		(fp_line
			(start -1.2954 0.5842)
			(end 1.2954 0.5842)
			(stroke
				(width 0.1524)
				(type default)
			)
			(layer "B.SilkS")
		)
		(fp_line
			(start 1.2954 0.5842)
			(end 1.2954 -0.5842)
			(stroke
				(width 0.1524)
				(type default)
			)
			(layer "B.SilkS")
		)
		(fp_line
			(start -1.2954 -0.5842)
			(end -1.2954 0.5842)
			(stroke
				(width 0.1524)
				(type default)
			)
			(layer "B.SilkS")
		)
		(fp_line
			(start 1.2954 -0.5842)
			(end -1.2954 -0.5842)
			(stroke
				(width 0.1524)
				(type default)
			)
			(layer "B.SilkS")
		)
		(fp_line
			(start -0.8636 0.4572)
			(end 0.8636 0.4572)
			(stroke
				(width 0.1)
				(type default)
			)
			(layer "B.Fab")
		)
		(fp_line
			(start 0.8636 0.4572)
			(end 0.8636 0.4318)
			(stroke
				(width 0.1)
				(type default)
			)
			(layer "B.Fab")
		)
		(fp_line
			(start 0.8636 0.4318)
			(end 0.8636 0.4064)
			(stroke
				(width 0.1)
				(type default)
			)
			(layer "B.Fab")
		)
		(fp_line
			(start -1.1938 0.4064)
			(end -0.8636 0.4064)
			(stroke
				(width 0.1)
				(type default)
			)
			(layer "B.Fab")
		)
		(fp_line
			(start -0.8636 0.4064)
			(end -0.8636 0.4572)
			(stroke
				(width 0.1)
				(type default)
			)
			(layer "B.Fab")
		)
		(fp_line
			(start 0.8636 0.4064)
			(end 1.1938 0.4064)
			(stroke
				(width 0.1)
				(type default)
			)
			(layer "B.Fab")
		)
		(fp_line
			(start 1.1938 0.4064)
			(end 1.1938 -0.406654)
			(stroke
				(width 0.1)
				(type default)
			)
			(layer "B.Fab")
		)
		(fp_line
			(start -1.1938 -0.406654)
			(end -1.1938 0.4064)
			(stroke
				(width 0.1)
				(type default)
			)
			(layer "B.Fab")
		)
		(fp_line
			(start -0.8636 -0.406654)
			(end -1.1938 -0.406654)
			(stroke
				(width 0.1)
				(type default)
			)
			(layer "B.Fab")
		)
		(fp_line
			(start 0.8636 -0.406654)
			(end 0.8636 -0.4572)
			(stroke
				(width 0.1)
				(type default)
			)
			(layer "B.Fab")
		)
		(fp_line
			(start 1.1938 -0.406654)
			(end 0.8636 -0.406654)
			(stroke
				(width 0.1)
				(type default)
			)
			(layer "B.Fab")
		)
		(fp_line
			(start -0.8636 -0.4572)
			(end -0.8636 -0.406654)
			(stroke
				(width 0.1)
				(type default)
			)
			(layer "B.Fab")
		)
		(fp_line
			(start 0.8636 -0.4572)
			(end -0.8636 -0.4572)
			(stroke
				(width 0.1)
				(type default)
			)
			(layer "B.Fab")
		)
		(pad "1" smd rect
			(at 0.7366 0 180)
			(size 0.7112 0.8128)
			(layers "B.Cu" "B.Mask" "B.Paste")
			(net "P3V3_DB2000_FB_VDD")
		)
		(pad "2" smd rect
			(at -0.7366 0 180)
			(size 0.7112 0.8128)
			(layers "B.Cu" "B.Mask" "B.Paste")
			(net "P3V3_DB2000_VDDA")
		)
	)
)
